#ISCELL
  cls sheet_a1 *
  *
#ISCELL
  cls gnd_sg *
  page3_i1
#ISCELL
  cls offpage_out *
  page3_i10
#CELL
  stdlogic g220_10198_01 *
  page3_i100
#CELL
  passive resistor *
  page3_i103
#ISCELL
  cls offpage_bi *
  page3_i109
#ISCELL
  cls offpage_out *
  page3_i11
#ISCELL
  cls offpage_out *
  page3_i110
#ISCELL
  cls vcc *
  page3_i111
#ISCELL
  cls vcc *
  page3_i112
#ISCELL
  cls offpage_in *
  page3_i113
#CELL
  passive resistor *
  page3_i114
#CELL
  passive capacitor *
  page3_i115
#CELL
  passive capacitor *
  page3_i116
#CELL
  passive capacitor *
  page3_i117
#CELL
  passive capacitor *
  page3_i118
#CELL
  passive capacitor *
  page3_i119
#ISCELL
  cls offpage_in *
  page3_i12
#CELL
  passive capacitor *
  page3_i120
#CELL
  passive capacitor *
  page3_i121
#CELL
  passive resistor *
  page3_i122
#ISCELL
  cls offpage_out *
  page3_i123
#CELL
  passive capacitor *
  page3_i124
#ISCELL
  cls gnd_sg *
  page3_i125
#CELL
  passive capacitor *
  page3_i126
#CELL
  passive capacitor *
  page3_i127
#ISCELL
  cls gnd_sg *
  page3_i128
#CELL
  passive capacitor *
  page3_i129
#ISCELL
  cls offpage_out *
  page3_i13
#ISCELL
  cls vcc *
  page3_i130
#ISCELL
  cls vcc *
  page3_i131
#CELL
  passive ferritebead *
  page3_i132
#ISCELL
  cls vcc *
  page3_i133
#CELL
  stdlogic 74lvc1g07_sc70_5 *
  page3_i134
#CELL
  stdlogic 74lvc1g07_sc70_5 *
  page3_i135
#ISCELL
  cls offpage_in *
  page3_i138
#CELL
  analog tps3808g18dbvr_sot23_6 *
  page3_i139
#ISCELL
  cls offpage_out *
  page3_i14
#ISCELL
  cls vcc *
  page3_i140
#ISCELL
  cls offpage_out *
  page3_i141
#CELL
  passive resistor *
  page3_i144
#CELL
  passive resistor *
  page3_i148
#ISCELL
  cls vcc *
  page3_i149
#CELL
  passive resistor *
  page3_i15
#ISCELL
  cls gnd_sg *
  page3_i150
#CELL
  passive resistor *
  page3_i151
#CELL
  passive capacitor *
  page3_i152
#CELL
  passive resistor *
  page3_i153
#ISCELL
  cls offpage_out *
  page3_i154
#ISCELL
  cls offpage_in *
  page3_i155
#CELL
  passive resistor *
  page3_i16
#ISCELL
  cls gnd_sg *
  page3_i18
#ISCELL
  cls vcc *
  page3_i19
#ISCELL
  cls gnd_sg *
  page3_i20
#ISCELL
  cls vcc *
  page3_i23
#ISCELL
  cls vcc *
  page3_i24
#ISCELL
  cls vcc *
  page3_i25
#ISCELL
  cls gnd_sg *
  page3_i26
#CELL
  passive capacitor *
  page3_i35
#CELL
  passive capacitor *
  page3_i36
#CELL
  passive capacitor *
  page3_i37
#ISCELL
  cls offpage_in *
  page3_i39
#CELL
  passive capacitor *
  page3_i4
#ISCELL
  cls offpage_in *
  page3_i40
#ISCELL
  cls offpage_in *
  page3_i41
#ISCELL
  cls offpage_in *
  page3_i42
#ISCELL
  cls offpage_in *
  page3_i43
#ISCELL
  cls offpage_in *
  page3_i44
#ISCELL
  cls offpage_in *
  page3_i45
#ISCELL
  cls offpage_in *
  page3_i46
#ISCELL
  cls offpage_out *
  page3_i47
#ISCELL
  cls offpage_out *
  page3_i48
#ISCELL
  cls vcc *
  page3_i49
#ISCELL
  cls offpage_out *
  page3_i5
#CELL
  passive resistor *
  page3_i51
#CELL
  passive resistor *
  page3_i52
#CELL
  passive resistor *
  page3_i53
#CELL
  passive resistor *
  page3_i54
#ISCELL
  cls offpage_in *
  page3_i55
#ISCELL
  cls offpage_out *
  page3_i56
#ISCELL
  cls offpage_in *
  page3_i57
#ISCELL
  cls offpage_out *
  page3_i58
#ISCELL
  cls offpage_out *
  page3_i59
#ISCELL
  cls offpage_in *
  page3_i6
#CELL
  connector conn_64p_gf *
  page3_i61
#CELL
  passive resistor *
  page3_i62
#CELL
  passive resistor *
  page3_i63
#ISCELL
  cls offpage_out *
  page3_i7
#ISCELL
  cls offpage_out *
  page3_i8
#ISCELL
  cls offpage_bi *
  page3_i81
#ISCELL
  cls offpage_bi *
  page3_i82
#ISCELL
  cls offpage_bi *
  page3_i86
#ISCELL
  cls offpage_in *
  page3_i87
#ISCELL
  cls offpage_out *
  page3_i9
#ISCELL
  cls gnd_sg *
  page3_i91
#CELL
  passive capacitor *
  page3_i92
#ISCELL
  cls gnd_sg *
  page3_i94
